(kicad_pcb
	(version 20260206)
	(generator "pcbnew")
	(generator_version "10.0")
	(general
		(thickness 1.6)
		(legacy_teardrops no)
	)
	(paper "A4")
	(title_block
		(title "12092022_DA0F0TMDCD0_F0T_Management_Board_D_brd_V3_OCP.brd")
		(comment 1 "Grand Teton / footprints 762-767 of 1440")
	)
	(layers
		(0 "F.Cu" signal "TOP")
		(4 "In1.Cu" signal "GND")
		(6 "In2.Cu" signal "IN1")
		(8 "In3.Cu" signal "GND1")
		(10 "In4.Cu" signal "IN2")
		(12 "In5.Cu" signal "VCC")
		(14 "In6.Cu" signal "VCC1")
		(16 "In7.Cu" signal "IN3")
		(18 "In8.Cu" signal "GND2")
		(20 "In9.Cu" signal "IN4")
		(22 "In10.Cu" signal "GND3")
		(2 "B.Cu" signal "BOTTOM")
		(9 "F.Adhes" user "F.Adhesive")
		(11 "B.Adhes" user "B.Adhesive")
		(13 "F.Paste" user "Package Geometry/Pastemask Top")
		(15 "B.Paste" user "Package Geometry/Pastemask Bottom")
		(5 "F.SilkS" user "Ref Des/Silkscreen Top")
		(7 "B.SilkS" user "Ref Des/Silkscreen Bottom")
		(1 "F.Mask" user "Board Geometry/Soldermask Top")
		(3 "B.Mask" user "Board Geometry/Soldermask Bottom")
		(17 "Dwgs.User" user "User.Drawings")
		(19 "Cmts.User" user "User.Comments")
		(21 "Eco1.User" user "User.Eco1")
		(23 "Eco2.User" user "User.Eco2")
		(25 "Edge.Cuts" user "Board Geometry/Outline")
		(27 "Margin" user)
		(31 "F.CrtYd" user "Package Geometry/Place Bound Top")
		(29 "B.CrtYd" user "Package Geometry/Place Bound Bottom")
		(35 "F.Fab" user "Ref Des/Assembly Top")
		(33 "B.Fab" user "Ref Des/Assembly Bottom")
	)
	(footprint ""
		(layer "B.Cu")
		(at 66.513202 -37.038788 90)
		(property "Reference" "R206"
			(at 0 0 90)
			(layer "B.SilkS")
			(hide yes)
			(effects
				(font
					(size 1.27 1.27)
				)
				(justify mirror)
			)
		)
		(property "Value" ""
			(at 0 0 90)
			(layer "B.Fab")
			(effects
				(font
					(size 1.27 1.27)
				)
				(justify mirror)
			)
		)
		(duplicate_pad_numbers_are_jumpers no)
		(fp_line
			(start 0.7874 -0.4064)
			(end -0.7874 -0.4064)
			(stroke
				(width 0.1524)
				(type default)
			)
			(layer "B.SilkS")
		)
		(fp_line
			(start -0.7874 -0.4064)
			(end -0.7874 0.4064)
			(stroke
				(width 0.1524)
				(type default)
			)
			(layer "B.SilkS")
		)
		(fp_line
			(start 0.7874 0.4064)
			(end 0.7874 -0.4064)
			(stroke
				(width 0.1524)
				(type default)
			)
			(layer "B.SilkS")
		)
		(fp_line
			(start -0.7874 0.4064)
			(end 0.7874 0.4064)
			(stroke
				(width 0.1524)
				(type default)
			)
			(layer "B.SilkS")
		)
		(fp_line
			(start 0.67945 -0.305054)
			(end 0.12065 -0.305054)
			(stroke
				(width 0.1)
				(type default)
			)
			(layer "B.Fab")
		)
		(fp_line
			(start 0.12065 -0.305054)
			(end 0.12065 -0.2794)
			(stroke
				(width 0.1)
				(type default)
			)
			(layer "B.Fab")
		)
		(fp_line
			(start -0.12065 -0.3048)
			(end -0.67945 -0.3048)
			(stroke
				(width 0.1)
				(type default)
			)
			(layer "B.Fab")
		)
		(fp_line
			(start -0.67945 -0.3048)
			(end -0.67945 0.3048)
			(stroke
				(width 0.1)
				(type default)
			)
			(layer "B.Fab")
		)
		(fp_line
			(start 0.12065 -0.2794)
			(end -0.12065 -0.2794)
			(stroke
				(width 0.1)
				(type default)
			)
			(layer "B.Fab")
		)
		(fp_line
			(start -0.12065 -0.2794)
			(end -0.12065 -0.3048)
			(stroke
				(width 0.1)
				(type default)
			)
			(layer "B.Fab")
		)
		(fp_line
			(start 0.12065 0.2794)
			(end 0.12065 0.3048)
			(stroke
				(width 0.1)
				(type default)
			)
			(layer "B.Fab")
		)
		(fp_line
			(start -0.120396 0.2794)
			(end 0.12065 0.2794)
			(stroke
				(width 0.1)
				(type default)
			)
			(layer "B.Fab")
		)
		(fp_line
			(start 0.67945 0.3048)
			(end 0.67945 -0.305054)
			(stroke
				(width 0.1)
				(type default)
			)
			(layer "B.Fab")
		)
		(fp_line
			(start 0.12065 0.3048)
			(end 0.67945 0.3048)
			(stroke
				(width 0.1)
				(type default)
			)
			(layer "B.Fab")
		)
		(fp_line
			(start -0.120396 0.3048)
			(end -0.120396 0.2794)
			(stroke
				(width 0.1)
				(type default)
			)
			(layer "B.Fab")
		)
		(fp_line
			(start -0.67945 0.3048)
			(end -0.120396 0.3048)
			(stroke
				(width 0.1)
				(type default)
			)
			(layer "B.Fab")
		)
		(pad "1" smd circle
			(at 0.40005 0 270)
			(size 0 0)
			(layers "B.Cu" "B.Mask" "B.Paste")
			(net "GND")
		)
		(pad "2" smd circle
			(at -0.40005 0 270)
			(size 0 0)
			(layers "B.Cu" "B.Mask" "B.Paste")
			(net "JTAG_SCM_NTRST")
		)
	)
	(footprint ""
		(layer "B.Cu")
		(at 49.3014 -66.72072 90)
		(property "Reference" "C311"
			(at 0 0 90)
			(layer "B.SilkS")
			(hide yes)
			(effects
				(font
					(size 1.27 1.27)
				)
				(justify mirror)
			)
		)
		(property "Value" ""
			(at 0 0 90)
			(layer "B.Fab")
			(effects
				(font
					(size 1.27 1.27)
				)
				(justify mirror)
			)
		)
		(duplicate_pad_numbers_are_jumpers no)
		(fp_line
			(start 0.7874 -0.4064)
			(end -0.7874 -0.4064)
			(stroke
				(width 0.1524)
				(type default)
			)
			(layer "B.SilkS")
		)
		(fp_line
			(start -0.7874 -0.4064)
			(end -0.7874 0.4064)
			(stroke
				(width 0.1524)
				(type default)
			)
			(layer "B.SilkS")
		)
		(fp_line
			(start 0.7874 0.4064)
			(end 0.7874 -0.4064)
			(stroke
				(width 0.1524)
				(type default)
			)
			(layer "B.SilkS")
		)
		(fp_line
			(start -0.7874 0.4064)
			(end 0.7874 0.4064)
			(stroke
				(width 0.1524)
				(type default)
			)
			(layer "B.SilkS")
		)
		(fp_line
			(start 0.67945 -0.305054)
			(end 0.12065 -0.305054)
			(stroke
				(width 0.1)
				(type default)
			)
			(layer "B.Fab")
		)
		(fp_line
			(start 0.12065 -0.305054)
			(end 0.12065 -0.2794)
			(stroke
				(width 0.1)
				(type default)
			)
			(layer "B.Fab")
		)
		(fp_line
			(start -0.12065 -0.3048)
			(end -0.67945 -0.3048)
			(stroke
				(width 0.1)
				(type default)
			)
			(layer "B.Fab")
		)
		(fp_line
			(start -0.67945 -0.3048)
			(end -0.67945 0.3048)
			(stroke
				(width 0.1)
				(type default)
			)
			(layer "B.Fab")
		)
		(fp_line
			(start 0.12065 -0.2794)
			(end -0.12065 -0.2794)
			(stroke
				(width 0.1)
				(type default)
			)
			(layer "B.Fab")
		)
		(fp_line
			(start -0.12065 -0.2794)
			(end -0.12065 -0.3048)
			(stroke
				(width 0.1)
				(type default)
			)
			(layer "B.Fab")
		)
		(fp_line
			(start 0.12065 0.2794)
			(end 0.12065 0.3048)
			(stroke
				(width 0.1)
				(type default)
			)
			(layer "B.Fab")
		)
		(fp_line
			(start -0.120396 0.2794)
			(end 0.12065 0.2794)
			(stroke
				(width 0.1)
				(type default)
			)
			(layer "B.Fab")
		)
		(fp_line
			(start 0.67945 0.3048)
			(end 0.67945 -0.305054)
			(stroke
				(width 0.1)
				(type default)
			)
			(layer "B.Fab")
		)
		(fp_line
			(start 0.12065 0.3048)
			(end 0.67945 0.3048)
			(stroke
				(width 0.1)
				(type default)
			)
			(layer "B.Fab")
		)
		(fp_line
			(start -0.120396 0.3048)
			(end -0.120396 0.2794)
			(stroke
				(width 0.1)
				(type default)
			)
			(layer "B.Fab")
		)
		(fp_line
			(start -0.67945 0.3048)
			(end -0.120396 0.3048)
			(stroke
				(width 0.1)
				(type default)
			)
			(layer "B.Fab")
		)
		(pad "1" smd circle
			(at 0.40005 0 270)
			(size 0 0)
			(layers "B.Cu" "B.Mask" "B.Paste")
			(net "P1V0_SENSOR")
		)
		(pad "2" smd circle
			(at -0.40005 0 270)
			(size 0 0)
			(layers "B.Cu" "B.Mask" "B.Paste")
			(net "GND")
		)
	)
	(footprint ""
		(layer "B.Cu")
		(at 64.794384 -40.322754)
		(property "Reference" "R387"
			(at 0 0 0)
			(layer "B.SilkS")
			(hide yes)
			(effects
				(font
					(size 1.27 1.27)
				)
				(justify mirror)
			)
		)
		(property "Value" ""
			(at 0 0 0)
			(layer "B.Fab")
			(effects
				(font
					(size 1.27 1.27)
				)
				(justify mirror)
			)
		)
		(duplicate_pad_numbers_are_jumpers no)
		(fp_line
			(start -0.7874 -0.4064)
			(end -0.7874 0.4064)
			(stroke
				(width 0.1524)
				(type default)
			)
			(layer "B.SilkS")
		)
		(fp_line
			(start -0.7874 0.4064)
			(end 0.7874 0.4064)
			(stroke
				(width 0.1524)
				(type default)
			)
			(layer "B.SilkS")
		)
		(fp_line
			(start 0.7874 -0.4064)
			(end -0.7874 -0.4064)
			(stroke
				(width 0.1524)
				(type default)
			)
			(layer "B.SilkS")
		)
		(fp_line
			(start 0.7874 0.4064)
			(end 0.7874 -0.4064)
			(stroke
				(width 0.1524)
				(type default)
			)
			(layer "B.SilkS")
		)
		(fp_line
			(start -0.67945 -0.3048)
			(end -0.67945 0.3048)
			(stroke
				(width 0.1)
				(type default)
			)
			(layer "B.Fab")
		)
		(fp_line
			(start -0.67945 0.3048)
			(end -0.120396 0.3048)
			(stroke
				(width 0.1)
				(type default)
			)
			(layer "B.Fab")
		)
		(fp_line
			(start -0.12065 -0.3048)
			(end -0.67945 -0.3048)
			(stroke
				(width 0.1)
				(type default)
			)
			(layer "B.Fab")
		)
		(fp_line
			(start -0.12065 -0.2794)
			(end -0.12065 -0.3048)
			(stroke
				(width 0.1)
				(type default)
			)
			(layer "B.Fab")
		)
		(fp_line
			(start -0.120396 0.2794)
			(end 0.12065 0.2794)
			(stroke
				(width 0.1)
				(type default)
			)
			(layer "B.Fab")
		)
		(fp_line
			(start -0.120396 0.3048)
			(end -0.120396 0.2794)
			(stroke
				(width 0.1)
				(type default)
			)
			(layer "B.Fab")
		)
		(fp_line
			(start 0.12065 -0.305054)
			(end 0.12065 -0.2794)
			(stroke
				(width 0.1)
				(type default)
			)
			(layer "B.Fab")
		)
		(fp_line
			(start 0.12065 -0.2794)
			(end -0.12065 -0.2794)
			(stroke
				(width 0.1)
				(type default)
			)
			(layer "B.Fab")
		)
		(fp_line
			(start 0.12065 0.2794)
			(end 0.12065 0.3048)
			(stroke
				(width 0.1)
				(type default)
			)
			(layer "B.Fab")
		)
		(fp_line
			(start 0.12065 0.3048)
			(end 0.67945 0.3048)
			(stroke
				(width 0.1)
				(type default)
			)
			(layer "B.Fab")
		)
		(fp_line
			(start 0.67945 -0.305054)
			(end 0.12065 -0.305054)
			(stroke
				(width 0.1)
				(type default)
			)
			(layer "B.Fab")
		)
		(fp_line
			(start 0.67945 0.3048)
			(end 0.67945 -0.305054)
			(stroke
				(width 0.1)
				(type default)
			)
			(layer "B.Fab")
		)
		(pad "1" smd circle
			(at 0.40005 0 180)
			(size 0 0)
			(layers "B.Cu" "B.Mask" "B.Paste")
			(net "GND")
		)
		(pad "2" smd circle
			(at -0.40005 0 180)
			(size 0 0)
			(layers "B.Cu" "B.Mask" "B.Paste")
			(net "DP_BMC_HPD_3V3_BUF")
		)
	)
	(footprint ""
		(layer "B.Cu")
		(at 50.673 -30.861 -90)
		(property "Reference" "R264"
			(at 0 0 90)
			(layer "B.SilkS")
			(hide yes)
			(effects
				(font
					(size 1.27 1.27)
				)
				(justify mirror)
			)
		)
		(property "Value" ""
			(at 0 0 90)
			(layer "B.Fab")
			(effects
				(font
					(size 1.27 1.27)
				)
				(justify mirror)
			)
		)
		(duplicate_pad_numbers_are_jumpers no)
		(fp_line
			(start -0.7874 0.4064)
			(end 0.7874 0.4064)
			(stroke
				(width 0.1524)
				(type default)
			)
			(layer "B.SilkS")
		)
		(fp_line
			(start 0.7874 0.4064)
			(end 0.7874 -0.4064)
			(stroke
				(width 0.1524)
				(type default)
			)
			(layer "B.SilkS")
		)
		(fp_line
			(start -0.7874 -0.4064)
			(end -0.7874 0.4064)
			(stroke
				(width 0.1524)
				(type default)
			)
			(layer "B.SilkS")
		)
		(fp_line
			(start 0.7874 -0.4064)
			(end -0.7874 -0.4064)
			(stroke
				(width 0.1524)
				(type default)
			)
			(layer "B.SilkS")
		)
		(fp_line
			(start -0.67945 0.3048)
			(end -0.120396 0.3048)
			(stroke
				(width 0.1)
				(type default)
			)
			(layer "B.Fab")
		)
		(fp_line
			(start -0.120396 0.3048)
			(end -0.120396 0.2794)
			(stroke
				(width 0.1)
				(type default)
			)
			(layer "B.Fab")
		)
		(fp_line
			(start 0.12065 0.3048)
			(end 0.67945 0.3048)
			(stroke
				(width 0.1)
				(type default)
			)
			(layer "B.Fab")
		)
		(fp_line
			(start 0.67945 0.3048)
			(end 0.67945 -0.305054)
			(stroke
				(width 0.1)
				(type default)
			)
			(layer "B.Fab")
		)
		(fp_line
			(start -0.120396 0.2794)
			(end 0.12065 0.2794)
			(stroke
				(width 0.1)
				(type default)
			)
			(layer "B.Fab")
		)
		(fp_line
			(start 0.12065 0.2794)
			(end 0.12065 0.3048)
			(stroke
				(width 0.1)
				(type default)
			)
			(layer "B.Fab")
		)
		(fp_line
			(start -0.12065 -0.2794)
			(end -0.12065 -0.3048)
			(stroke
				(width 0.1)
				(type default)
			)
			(layer "B.Fab")
		)
		(fp_line
			(start 0.12065 -0.2794)
			(end -0.12065 -0.2794)
			(stroke
				(width 0.1)
				(type default)
			)
			(layer "B.Fab")
		)
		(fp_line
			(start -0.67945 -0.3048)
			(end -0.67945 0.3048)
			(stroke
				(width 0.1)
				(type default)
			)
			(layer "B.Fab")
		)
		(fp_line
			(start -0.12065 -0.3048)
			(end -0.67945 -0.3048)
			(stroke
				(width 0.1)
				(type default)
			)
			(layer "B.Fab")
		)
		(fp_line
			(start 0.12065 -0.305054)
			(end 0.12065 -0.2794)
			(stroke
				(width 0.1)
				(type default)
			)
			(layer "B.Fab")
		)
		(fp_line
			(start 0.67945 -0.305054)
			(end 0.12065 -0.305054)
			(stroke
				(width 0.1)
				(type default)
			)
			(layer "B.Fab")
		)
		(pad "1" smd circle
			(at 0.40005 0 90)
			(size 0 0)
			(layers "B.Cu" "B.Mask" "B.Paste")
			(net "P3V3_AUX")
		)
		(pad "2" smd circle
			(at -0.40005 0 90)
			(size 0 0)
			(layers "B.Cu" "B.Mask" "B.Paste")
			(net "SMB_BMC_MM16_SCL")
		)
	)
	(footprint ""
		(layer "B.Cu")
		(at 58.7375 -15.6337 -90)
		(property "Reference" "Q6"
			(at 2.52857 -1.4605 0)
			(unlocked yes)
			(layer "B.SilkS")
			(effects
				(font
					(size 0.7874 0.5842)
					(thickness 0.1524)
				)
				(justify left mirror)
			)
		)
		(property "Value" ""
			(at 0 0 90)
			(layer "B.Fab")
			(effects
				(font
					(size 1.27 1.27)
				)
				(justify mirror)
			)
		)
		(duplicate_pad_numbers_are_jumpers no)
		(fp_line
			(start -1.603248 1.500124)
			(end 1.603248 1.500124)
			(stroke
				(width 0.1524)
				(type default)
			)
			(layer "B.SilkS")
		)
		(fp_line
			(start 1.603248 1.500124)
			(end 1.603248 -1.500124)
			(stroke
				(width 0.1524)
				(type default)
			)
			(layer "B.SilkS")
		)
		(fp_line
			(start -1.603248 -1.500124)
			(end -1.603248 1.500124)
			(stroke
				(width 0.1524)
				(type default)
			)
			(layer "B.SilkS")
		)
		(fp_line
			(start 1.603248 -1.500124)
			(end -1.603248 -1.500124)
			(stroke
				(width 0.1524)
				(type default)
			)
			(layer "B.SilkS")
		)
		(fp_line
			(start -0.700024 1.500124)
			(end -0.700024 0.219964)
			(stroke
				(width 0.1)
				(type default)
			)
			(layer "B.Fab")
		)
		(fp_line
			(start 0.700024 1.500124)
			(end -0.700024 1.500124)
			(stroke
				(width 0.1)
				(type default)
			)
			(layer "B.Fab")
		)
		(fp_line
			(start 0.700024 1.169924)
			(end 0.700024 1.500124)
			(stroke
				(width 0.1)
				(type default)
			)
			(layer "B.Fab")
		)
		(fp_line
			(start 1.249934 1.169924)
			(end 0.700024 1.169924)
			(stroke
				(width 0.1)
				(type default)
			)
			(layer "B.Fab")
		)
		(fp_line
			(start 0.6985 0.729996)
			(end 1.249934 0.729996)
			(stroke
				(width 0.1)
				(type default)
			)
			(layer "B.Fab")
		)
		(fp_line
			(start 1.249934 0.729996)
			(end 1.249934 1.169924)
			(stroke
				(width 0.1)
				(type default)
			)
			(layer "B.Fab")
		)
		(fp_line
			(start -1.249934 0.219964)
			(end -1.249934 -0.219964)
			(stroke
				(width 0.1)
				(type default)
			)
			(layer "B.Fab")
		)
		(fp_line
			(start -0.700024 0.219964)
			(end -1.249934 0.219964)
			(stroke
				(width 0.1)
				(type default)
			)
			(layer "B.Fab")
		)
		(fp_line
			(start -1.249934 -0.219964)
			(end -0.700024 -0.219964)
			(stroke
				(width 0.1)
				(type default)
			)
			(layer "B.Fab")
		)
		(fp_line
			(start -0.700024 -0.219964)
			(end -0.700024 -1.500124)
			(stroke
				(width 0.1)
				(type default)
			)
			(layer "B.Fab")
		)
		(fp_line
			(start 0.6985 -0.729996)
			(end 0.6985 0.729996)
			(stroke
				(width 0.1)
				(type default)
			)
			(layer "B.Fab")
		)
		(fp_line
			(start 1.249934 -0.729996)
			(end 0.6985 -0.729996)
			(stroke
				(width 0.1)
				(type default)
			)
			(layer "B.Fab")
		)
		(fp_line
			(start 0.700024 -1.169924)
			(end 1.249934 -1.169924)
			(stroke
				(width 0.1)
				(type default)
			)
			(layer "B.Fab")
		)
		(fp_line
			(start 1.249934 -1.169924)
			(end 1.249934 -0.729996)
			(stroke
				(width 0.1)
				(type default)
			)
			(layer "B.Fab")
		)
		(fp_line
			(start -0.700024 -1.500124)
			(end 0.700024 -1.500124)
			(stroke
				(width 0.1)
				(type default)
			)
			(layer "B.Fab")
		)
		(fp_line
			(start 0.700024 -1.500124)
			(end 0.700024 -1.169924)
			(stroke
				(width 0.1)
				(type default)
			)
			(layer "B.Fab")
		)
		(fp_rect
			(start 0.700024 1.500124)
			(end -0.700024 -1.500124)
			(stroke
				(width 0)
				(type default)
			)
			(fill no)
			(layer "B.Fab")
		)
		(pad "D" smd rect
			(at -0.999998 0 180)
			(size 0.8128 0.9144)
			(layers "B.Cu" "B.Mask" "B.Paste")
			(net "FM_DEBUG_PORT_R_PRSNT_N")
		)
		(pad "G" smd rect
			(at 0.999998 -0.94996 180)
			(size 0.8128 0.9144)
			(layers "B.Cu" "B.Mask" "B.Paste")
			(net "DEBUG_PORT_PRSNT")
		)
		(pad "S" smd rect
			(at 0.999998 0.94996 180)
			(size 0.8128 0.9144)
			(layers "B.Cu" "B.Mask" "B.Paste")
			(net "GND")
		)
	)
	(footprint ""
		(layer "B.Cu")
		(at 63.129922 -49.472088 180)
		(property "Reference" "C73"
			(at 0 0 0)
			(layer "B.SilkS")
			(hide yes)
			(effects
				(font
					(size 1.27 1.27)
				)
				(justify mirror)
			)
		)
		(property "Value" ""
			(at 0 0 0)
			(layer "B.Fab")
			(effects
				(font
					(size 1.27 1.27)
				)
				(justify mirror)
			)
		)
		(duplicate_pad_numbers_are_jumpers no)
		(fp_line
			(start 0.7874 0.4064)
			(end 0.7874 -0.4064)
			(stroke
				(width 0.1524)
				(type default)
			)
			(layer "B.SilkS")
		)
		(fp_line
			(start 0.7874 -0.4064)
			(end -0.7874 -0.4064)
			(stroke
				(width 0.1524)
				(type default)
			)
			(layer "B.SilkS")
		)
		(fp_line
			(start -0.7874 0.4064)
			(end 0.7874 0.4064)
			(stroke
				(width 0.1524)
				(type default)
			)
			(layer "B.SilkS")
		)
		(fp_line
			(start -0.7874 -0.4064)
			(end -0.7874 0.4064)
			(stroke
				(width 0.1524)
				(type default)
			)
			(layer "B.SilkS")
		)
		(fp_line
			(start 0.67945 0.3048)
			(end 0.67945 -0.305054)
			(stroke
				(width 0.1)
				(type default)
			)
			(layer "B.Fab")
		)
		(fp_line
			(start 0.67945 -0.305054)
			(end 0.12065 -0.305054)
			(stroke
				(width 0.1)
				(type default)
			)
			(layer "B.Fab")
		)
		(fp_line
			(start 0.12065 0.3048)
			(end 0.67945 0.3048)
			(stroke
				(width 0.1)
				(type default)
			)
			(layer "B.Fab")
		)
		(fp_line
			(start 0.12065 0.2794)
			(end 0.12065 0.3048)
			(stroke
				(width 0.1)
				(type default)
			)
			(layer "B.Fab")
		)
		(fp_line
			(start 0.12065 -0.2794)
			(end -0.12065 -0.2794)
			(stroke
				(width 0.1)
				(type default)
			)
			(layer "B.Fab")
		)
		(fp_line
			(start 0.12065 -0.305054)
			(end 0.12065 -0.2794)
			(stroke
				(width 0.1)
				(type default)
			)
			(layer "B.Fab")
		)
		(fp_line
			(start -0.120396 0.3048)
			(end -0.120396 0.2794)
			(stroke
				(width 0.1)
				(type default)
			)
			(layer "B.Fab")
		)
		(fp_line
			(start -0.120396 0.2794)
			(end 0.12065 0.2794)
			(stroke
				(width 0.1)
				(type default)
			)
			(layer "B.Fab")
		)
		(fp_line
			(start -0.12065 -0.2794)
			(end -0.12065 -0.3048)
			(stroke
				(width 0.1)
				(type default)
			)
			(layer "B.Fab")
		)
		(fp_line
			(start -0.12065 -0.3048)
			(end -0.67945 -0.3048)
			(stroke
				(width 0.1)
				(type default)
			)
			(layer "B.Fab")
		)
		(fp_line
			(start -0.67945 0.3048)
			(end -0.120396 0.3048)
			(stroke
				(width 0.1)
				(type default)
			)
			(layer "B.Fab")
		)
		(fp_line
			(start -0.67945 -0.3048)
			(end -0.67945 0.3048)
			(stroke
				(width 0.1)
				(type default)
			)
			(layer "B.Fab")
		)
		(pad "1" smd circle
			(at 0.40005 0)
			(size 0 0)
			(layers "B.Cu" "B.Mask" "B.Paste")
			(net "P1V2_STBY_MVDD_CK")
		)
		(pad "2" smd circle
			(at -0.40005 0)
			(size 0 0)
			(layers "B.Cu" "B.Mask" "B.Paste")
			(net "GND")
		)
	)
)
